(kicad_pcb
	(version 20260206)
	(generator "pcbnew")
	(generator_version "10.0")
	(general
		(thickness 1.6)
		(legacy_teardrops no)
	)
	(paper "A4")
	(title_block
		(title "Wiwynn_Tioga_Pass_MB.brd")
		(comment 1 "Tioga Pass / footprints 934-941 of 4770")
	)
	(layers
		(0 "F.Cu" signal "TOP")
		(4 "In1.Cu" signal "L2GND")
		(6 "In2.Cu" signal "L3")
		(8 "In3.Cu" signal "L4GND")
		(10 "In4.Cu" signal "L5")
		(12 "In5.Cu" signal "L6GND")
		(14 "In6.Cu" signal "L7VCC")
		(16 "In7.Cu" signal "L8VCC")
		(18 "In8.Cu" signal "L9GND")
		(20 "In9.Cu" signal "L10")
		(22 "In10.Cu" signal "L11GND")
		(24 "In11.Cu" signal "L12")
		(26 "In12.Cu" signal "L13GND")
		(2 "B.Cu" signal "BOTTOM")
		(9 "F.Adhes" user "F.Adhesive")
		(11 "B.Adhes" user "B.Adhesive")
		(13 "F.Paste" user "Package Geometry/Pastemask Top")
		(15 "B.Paste" user "Package Geometry/Pastemask Bottom")
		(5 "F.SilkS" user "Ref Des/Silkscreen Top")
		(7 "B.SilkS" user "Ref Des/Silkscreen Bottom")
		(1 "F.Mask" user "Board Geometry/Soldermask Top")
		(3 "B.Mask" user "Board Geometry/Soldermask Bottom")
		(17 "Dwgs.User" user "User.Drawings")
		(19 "Cmts.User" user "User.Comments")
		(21 "Eco1.User" user "User.Eco1")
		(23 "Eco2.User" user "User.Eco2")
		(25 "Edge.Cuts" user "Board Geometry/Outline")
		(27 "Margin" user)
		(31 "F.CrtYd" user "Package Geometry/Place Bound Top")
		(29 "B.CrtYd" user "Package Geometry/Place Bound Bottom")
		(35 "F.Fab" user "Ref Des/Assembly Top")
		(33 "B.Fab" user "Ref Des/Assembly Bottom")
	)
	(footprint ""
		(layer "F.Cu")
		(at 198.337932 -60.305442 90)
		(property "Reference" "C4E20"
			(at 0 0 90)
			(layer "F.SilkS")
			(hide yes)
			(effects
				(font
					(size 1.27 1.27)
				)
			)
		)
		(property "Value" ""
			(at 0 0 90)
			(layer "F.Fab")
			(effects
				(font
					(size 1.27 1.27)
				)
			)
		)
		(duplicate_pad_numbers_are_jumpers no)
		(fp_rect
			(start 0.3048 0.9906)
			(end -0.3048 -0.1016)
			(stroke
				(width 0)
				(type default)
			)
			(fill no)
			(layer "F.CrtYd")
		)
		(fp_line
			(start 0.3048 -0.1016)
			(end -0.3048 -0.1016)
			(stroke
				(width 0.1)
				(type default)
			)
			(layer "F.Fab")
		)
		(fp_line
			(start -0.3048 -0.1016)
			(end -0.3048 0.9906)
			(stroke
				(width 0.1)
				(type default)
			)
			(layer "F.Fab")
		)
		(fp_line
			(start 0.3048 0.9906)
			(end 0.3048 -0.1016)
			(stroke
				(width 0.1)
				(type default)
			)
			(layer "F.Fab")
		)
		(fp_line
			(start -0.3048 0.9906)
			(end 0.3048 0.9906)
			(stroke
				(width 0.1)
				(type default)
			)
			(layer "F.Fab")
		)
		(pad "1" smd rect
			(at 0 0 90)
			(size 0.508 0.508)
			(layers "F.Cu" "F.Mask" "F.Paste")
			(net "VR_FET_SW_P12V_STBY_PVCCIN_CPU0")
		)
		(pad "2" smd rect
			(at 0 0.889 90)
			(size 0.508 0.508)
			(layers "F.Cu" "F.Mask" "F.Paste")
			(net "GND")
		)
		(zone
			(layer "F.Cu")
			(hatch none 0.5)
			(connect_pads
				(clearance 0)
			)
			(min_thickness 0.25)
			(keepout
				(tracks not_allowed)
				(vias allowed)
				(pads allowed)
				(copperpour not_allowed)
				(footprints allowed)
			)
			(placement
				(enabled no)
				(sheetname "")
			)
			(fill
				(thermal_gap 0.5)
				(thermal_bridge_width 0.5)
				(island_removal_mode 0)
			)
			(polygon
				(pts
					(xy 198.972932 -60.559442) (xy 198.591932 -60.559442) (xy 198.591932 -60.051442) (xy 198.972932 -60.051442)
				)
			)
		)
		(zone
			(layer "F.Cu")
			(hatch none 0.5)
			(connect_pads
				(clearance 0)
			)
			(min_thickness 0.25)
			(keepout
				(tracks allowed)
				(vias not_allowed)
				(pads allowed)
				(copperpour not_allowed)
				(footprints allowed)
			)
			(placement
				(enabled no)
				(sheetname "")
			)
			(fill
				(thermal_gap 0.5)
				(thermal_bridge_width 0.5)
				(island_removal_mode 0)
			)
			(polygon
				(pts
					(xy 198.972932 -60.559442) (xy 198.591932 -60.559442) (xy 198.591932 -60.051442) (xy 198.972932 -60.051442)
				)
			)
		)
	)
	(footprint ""
		(layer "F.Cu")
		(at 365.890556 -156.250894 180)
		(property "Reference" "C7A13"
			(at 0 0 180)
			(layer "F.SilkS")
			(hide yes)
			(effects
				(font
					(size 1.27 1.27)
				)
			)
		)
		(property "Value" "*"
			(at -0.0762 -6.2357 180)
			(unlocked yes)
			(layer "F.Fab")
			(hide yes)
			(effects
				(font
					(size 1.27 1.016)
					(thickness 0.1524)
				)
			)
		)
		(property "Device Type" "SC22U16V5MX-4-GP_SMD-BCG5-SC22A"
			(at -0.0762 -8.2677 180)
			(unlocked yes)
			(layer "F.Fab")
			(hide yes)
			(effects
				(font
					(size 1.27 1.016)
					(thickness 0.1524)
				)
			)
		)
		(duplicate_pad_numbers_are_jumpers no)
		(fp_line
			(start 0.635 0)
			(end -0.635 0)
			(stroke
				(width 0.508)
				(type default)
			)
			(layer "F.SilkS")
		)
		(fp_rect
			(start -0.9652 1.778)
			(end 0.9652 -1.778)
			(stroke
				(width 0)
				(type default)
			)
			(fill no)
			(layer "F.CrtYd")
		)
		(fp_poly
			(pts
				(xy -0.9652 -1.778) (xy 0.9652 -1.778) (xy 0.9652 1.778) (xy -0.9652 1.778)
			)
			(stroke
				(width 0)
				(type default)
			)
			(fill no)
			(layer "F.Fab")
		)
		(pad "1" smd rect
			(at 0 -0.9652 180)
			(size 1.397 1.143)
			(layers "F.Cu" "F.Mask" "F.Paste")
			(net "VR_FET_SW_P12V_STBY_PVDDQ_DEF")
		)
		(pad "2" smd rect
			(at 0 0.9652 180)
			(size 1.397 1.143)
			(layers "F.Cu" "F.Mask" "F.Paste")
			(net "GND")
		)
	)
	(footprint ""
		(layer "F.Cu")
		(at 30.579568 -12.923012 90)
		(property "Reference" "C1G10"
			(at 0 0 90)
			(layer "F.SilkS")
			(hide yes)
			(effects
				(font
					(size 1.27 1.27)
				)
			)
		)
		(property "Value" ""
			(at 0 0 90)
			(layer "F.Fab")
			(effects
				(font
					(size 1.27 1.27)
				)
			)
		)
		(duplicate_pad_numbers_are_jumpers no)
		(fp_poly
			(pts
				(xy 0.3048 -0.1016) (xy 0.3048 0.9906) (xy -0.3048 0.9906) (xy -0.3048 -0.1016)
			)
			(stroke
				(width 0)
				(type default)
			)
			(fill no)
			(layer "F.CrtYd")
		)
		(fp_line
			(start 0.3048 -0.1016)
			(end -0.3048 -0.1016)
			(stroke
				(width 0.1)
				(type default)
			)
			(layer "F.Fab")
		)
		(fp_line
			(start -0.3048 -0.1016)
			(end -0.3048 0.9906)
			(stroke
				(width 0.1)
				(type default)
			)
			(layer "F.Fab")
		)
		(fp_line
			(start 0.3048 0.9906)
			(end 0.3048 -0.1016)
			(stroke
				(width 0.1)
				(type default)
			)
			(layer "F.Fab")
		)
		(fp_line
			(start -0.3048 0.9906)
			(end 0.3048 0.9906)
			(stroke
				(width 0.1)
				(type default)
			)
			(layer "F.Fab")
		)
		(pad "1" smd rect
			(at 0 0 90)
			(size 0.508 0.508)
			(layers "F.Cu" "F.Mask" "F.Paste")
			(net "M_H_VREF")
		)
		(pad "2" smd rect
			(at 0 0.889 90)
			(size 0.508 0.508)
			(layers "F.Cu" "F.Mask" "F.Paste")
			(net "GND")
		)
		(zone
			(layer "F.Cu")
			(hatch none 0.5)
			(connect_pads
				(clearance 0)
			)
			(min_thickness 0.25)
			(keepout
				(tracks allowed)
				(vias not_allowed)
				(pads allowed)
				(copperpour not_allowed)
				(footprints allowed)
			)
			(placement
				(enabled no)
				(sheetname "")
			)
			(fill
				(thermal_gap 0.5)
				(thermal_bridge_width 0.5)
				(island_removal_mode 0)
			)
			(polygon
				(pts
					(xy 30.833568 -12.669012) (xy 30.833568 -13.177012) (xy 31.214568 -13.177012) (xy 31.214568 -12.669012)
				)
			)
		)
		(zone
			(layer "F.Cu")
			(hatch none 0.5)
			(connect_pads
				(clearance 0)
			)
			(min_thickness 0.25)
			(keepout
				(tracks not_allowed)
				(vias allowed)
				(pads allowed)
				(copperpour not_allowed)
				(footprints allowed)
			)
			(placement
				(enabled no)
				(sheetname "")
			)
			(fill
				(thermal_gap 0.5)
				(thermal_bridge_width 0.5)
				(island_removal_mode 0)
			)
			(polygon
				(pts
					(xy 31.214568 -12.669012) (xy 31.214568 -13.177012) (xy 30.833568 -13.177012) (xy 30.833568 -12.669012)
				)
			)
		)
	)
	(footprint ""
		(layer "F.Cu")
		(at 341.249 -23.749)
		(property "Reference" "C7F8"
			(at 0 0 0)
			(layer "F.SilkS")
			(hide yes)
			(effects
				(font
					(size 1.27 1.27)
				)
			)
		)
		(property "Value" ""
			(at 0 0 0)
			(layer "F.Fab")
			(effects
				(font
					(size 1.27 1.27)
				)
			)
		)
		(duplicate_pad_numbers_are_jumpers no)
		(fp_rect
			(start 0.3048 0.9906)
			(end -0.3048 -0.1016)
			(stroke
				(width 0)
				(type default)
			)
			(fill no)
			(layer "F.CrtYd")
		)
		(fp_line
			(start -0.3048 -0.1016)
			(end -0.3048 0.9906)
			(stroke
				(width 0.1)
				(type default)
			)
			(layer "F.Fab")
		)
		(fp_line
			(start -0.3048 0.9906)
			(end 0.3048 0.9906)
			(stroke
				(width 0.1)
				(type default)
			)
			(layer "F.Fab")
		)
		(fp_line
			(start 0.3048 -0.1016)
			(end -0.3048 -0.1016)
			(stroke
				(width 0.1)
				(type default)
			)
			(layer "F.Fab")
		)
		(fp_line
			(start 0.3048 0.9906)
			(end 0.3048 -0.1016)
			(stroke
				(width 0.1)
				(type default)
			)
			(layer "F.Fab")
		)
		(pad "1" smd rect
			(at 0 0)
			(size 0.508 0.508)
			(layers "F.Cu" "F.Mask" "F.Paste")
			(net "FM_PVPP_CPU0_EN")
		)
		(pad "2" smd rect
			(at 0 0.889)
			(size 0.508 0.508)
			(layers "F.Cu" "F.Mask" "F.Paste")
			(net "AGND_PVPP_ABC")
		)
		(zone
			(layer "F.Cu")
			(hatch none 0.5)
			(connect_pads
				(clearance 0)
			)
			(min_thickness 0.25)
			(keepout
				(tracks allowed)
				(vias not_allowed)
				(pads allowed)
				(copperpour not_allowed)
				(footprints allowed)
			)
			(placement
				(enabled no)
				(sheetname "")
			)
			(fill
				(thermal_gap 0.5)
				(thermal_bridge_width 0.5)
				(island_removal_mode 0)
			)
			(polygon
				(pts
					(xy 341.503 -23.114) (xy 341.503 -23.495) (xy 340.995 -23.495) (xy 340.995 -23.114)
				)
			)
		)
		(zone
			(layer "F.Cu")
			(hatch none 0.5)
			(connect_pads
				(clearance 0)
			)
			(min_thickness 0.25)
			(keepout
				(tracks not_allowed)
				(vias allowed)
				(pads allowed)
				(copperpour not_allowed)
				(footprints allowed)
			)
			(placement
				(enabled no)
				(sheetname "")
			)
			(fill
				(thermal_gap 0.5)
				(thermal_bridge_width 0.5)
				(island_removal_mode 0)
			)
			(polygon
				(pts
					(xy 341.503 -23.114) (xy 341.503 -23.495) (xy 340.995 -23.495) (xy 340.995 -23.114)
				)
			)
		)
	)
	(footprint ""
		(layer "F.Cu")
		(at 394.143992 -10.917936)
		(property "Reference" "C7G22"
			(at 0 0 0)
			(layer "F.SilkS")
			(hide yes)
			(effects
				(font
					(size 1.27 1.27)
				)
			)
		)
		(property "Value" ""
			(at 0 0 0)
			(layer "F.Fab")
			(effects
				(font
					(size 1.27 1.27)
				)
			)
		)
		(duplicate_pad_numbers_are_jumpers no)
		(fp_rect
			(start -0.3048 0.9906)
			(end 0.3048 -0.1016)
			(stroke
				(width 0)
				(type default)
			)
			(fill no)
			(layer "F.CrtYd")
		)
		(fp_line
			(start -0.3048 -0.1016)
			(end -0.3048 0.9906)
			(stroke
				(width 0.1)
				(type default)
			)
			(layer "F.Fab")
		)
		(fp_line
			(start -0.3048 0.9906)
			(end 0.3048 0.9906)
			(stroke
				(width 0.1)
				(type default)
			)
			(layer "F.Fab")
		)
		(fp_line
			(start 0.3048 -0.1016)
			(end -0.3048 -0.1016)
			(stroke
				(width 0.1)
				(type default)
			)
			(layer "F.Fab")
		)
		(fp_line
			(start 0.3048 0.9906)
			(end 0.3048 -0.1016)
			(stroke
				(width 0.1)
				(type default)
			)
			(layer "F.Fab")
		)
		(pad "1" smd rect
			(at 0 0)
			(size 0.508 0.508)
			(layers "F.Cu" "F.Mask" "F.Paste")
			(net "P3E_CPU0_PE2_SS_TXN<7>")
		)
		(pad "2" smd rect
			(at 0 0.889)
			(size 0.508 0.508)
			(layers "F.Cu" "F.Mask" "F.Paste")
			(net "P3E_CPU0_PE2_SS_C_TXN<7>")
		)
		(zone
			(layer "F.Cu")
			(hatch none 0.5)
			(connect_pads
				(clearance 0)
			)
			(min_thickness 0.25)
			(keepout
				(tracks allowed)
				(vias not_allowed)
				(pads allowed)
				(copperpour not_allowed)
				(footprints allowed)
			)
			(placement
				(enabled no)
				(sheetname "")
			)
			(fill
				(thermal_gap 0.5)
				(thermal_bridge_width 0.5)
				(island_removal_mode 0)
			)
			(polygon
				(pts
					(xy 393.889992 -10.282936) (xy 394.397992 -10.282936) (xy 394.397992 -10.663936) (xy 393.889992 -10.663936)
				)
			)
		)
		(zone
			(layer "F.Cu")
			(hatch none 0.5)
			(connect_pads
				(clearance 0)
			)
			(min_thickness 0.25)
			(keepout
				(tracks not_allowed)
				(vias allowed)
				(pads allowed)
				(copperpour not_allowed)
				(footprints allowed)
			)
			(placement
				(enabled no)
				(sheetname "")
			)
			(fill
				(thermal_gap 0.5)
				(thermal_bridge_width 0.5)
				(island_removal_mode 0)
			)
			(polygon
				(pts
					(xy 393.889992 -10.282936) (xy 394.397992 -10.282936) (xy 394.397992 -10.663936) (xy 393.889992 -10.663936)
				)
			)
		)
	)
	(footprint ""
		(layer "F.Cu")
		(at 352.5012 -11.1506 -90)
		(property "Reference" "R7G25"
			(at 0 0 270)
			(layer "F.SilkS")
			(hide yes)
			(effects
				(font
					(size 1.27 1.27)
				)
			)
		)
		(property "Value" ""
			(at 0 0 270)
			(layer "F.Fab")
			(effects
				(font
					(size 1.27 1.27)
				)
			)
		)
		(duplicate_pad_numbers_are_jumpers no)
		(fp_poly
			(pts
				(xy -0.2794 -0.1016) (xy 0.2794 -0.1016) (xy 0.2794 0.9906) (xy -0.2794 0.9906)
			)
			(stroke
				(width 0)
				(type default)
			)
			(fill no)
			(layer "F.CrtYd")
		)
		(fp_line
			(start -0.2794 0.9906)
			(end 0.2794 0.9906)
			(stroke
				(width 0.1)
				(type default)
			)
			(layer "F.Fab")
		)
		(fp_line
			(start 0.2794 0.9906)
			(end 0.2794 -0.1016)
			(stroke
				(width 0.1)
				(type default)
			)
			(layer "F.Fab")
		)
		(fp_line
			(start -0.2794 -0.1016)
			(end -0.2794 0.9906)
			(stroke
				(width 0.1)
				(type default)
			)
			(layer "F.Fab")
		)
		(fp_line
			(start 0.2794 -0.1016)
			(end -0.2794 -0.1016)
			(stroke
				(width 0.1)
				(type default)
			)
			(layer "F.Fab")
		)
		(pad "1" smd rect
			(at 0 0 270)
			(size 0.508 0.508)
			(layers "F.Cu" "F.Mask" "F.Paste")
			(net "VR_PVDDQ_ABC_PH1_OCSET")
		)
		(pad "2" smd rect
			(at 0 0.889 270)
			(size 0.508 0.508)
			(layers "F.Cu" "F.Mask" "F.Paste")
			(net "GND")
		)
		(zone
			(layer "F.Cu")
			(hatch none 0.5)
			(connect_pads
				(clearance 0)
			)
			(min_thickness 0.25)
			(keepout
				(tracks not_allowed)
				(vias allowed)
				(pads allowed)
				(copperpour not_allowed)
				(footprints allowed)
			)
			(placement
				(enabled no)
				(sheetname "")
			)
			(fill
				(thermal_gap 0.5)
				(thermal_bridge_width 0.5)
				(island_removal_mode 0)
			)
			(polygon
				(pts
					(xy 351.8662 -11.4046) (xy 351.8662 -10.8966) (xy 352.2472 -10.8966) (xy 352.2472 -11.4046)
				)
			)
		)
		(zone
			(layer "F.Cu")
			(hatch none 0.5)
			(connect_pads
				(clearance 0)
			)
			(min_thickness 0.25)
			(keepout
				(tracks allowed)
				(vias not_allowed)
				(pads allowed)
				(copperpour not_allowed)
				(footprints allowed)
			)
			(placement
				(enabled no)
				(sheetname "")
			)
			(fill
				(thermal_gap 0.5)
				(thermal_bridge_width 0.5)
				(island_removal_mode 0)
			)
			(polygon
				(pts
					(xy 352.2472 -11.4046) (xy 352.2472 -10.8966) (xy 351.8662 -10.8966) (xy 351.8662 -11.4046)
				)
			)
		)
	)
	(footprint ""
		(layer "F.Cu")
		(at 419.3032 -18.7452)
		(property "Reference" "R9G14"
			(at 0 0 0)
			(layer "F.SilkS")
			(hide yes)
			(effects
				(font
					(size 1.27 1.27)
				)
			)
		)
		(property "Value" ""
			(at 0 0 0)
			(layer "F.Fab")
			(effects
				(font
					(size 1.27 1.27)
				)
			)
		)
		(duplicate_pad_numbers_are_jumpers no)
		(fp_poly
			(pts
				(xy -0.2794 -0.1016) (xy 0.2794 -0.1016) (xy 0.2794 0.9906) (xy -0.2794 0.9906)
			)
			(stroke
				(width 0)
				(type default)
			)
			(fill no)
			(layer "F.CrtYd")
		)
		(fp_line
			(start -0.2794 -0.1016)
			(end -0.2794 0.9906)
			(stroke
				(width 0.1)
				(type default)
			)
			(layer "F.Fab")
		)
		(fp_line
			(start -0.2794 0.9906)
			(end 0.2794 0.9906)
			(stroke
				(width 0.1)
				(type default)
			)
			(layer "F.Fab")
		)
		(fp_line
			(start 0.2794 -0.1016)
			(end -0.2794 -0.1016)
			(stroke
				(width 0.1)
				(type default)
			)
			(layer "F.Fab")
		)
		(fp_line
			(start 0.2794 0.9906)
			(end 0.2794 -0.1016)
			(stroke
				(width 0.1)
				(type default)
			)
			(layer "F.Fab")
		)
		(pad "1" smd rect
			(at 0 0)
			(size 0.508 0.508)
			(layers "F.Cu" "F.Mask" "F.Paste")
			(net "SMB_SENSOR_BMC_STBY_LVC3_SCL")
		)
		(pad "2" smd rect
			(at 0 0.889)
			(size 0.508 0.508)
			(layers "F.Cu" "F.Mask" "F.Paste")
			(net "SMB_SENSOR_STBY_LVC3_SCL")
		)
		(zone
			(layer "F.Cu")
			(hatch none 0.5)
			(connect_pads
				(clearance 0)
			)
			(min_thickness 0.25)
			(keepout
				(tracks allowed)
				(vias not_allowed)
				(pads allowed)
				(copperpour not_allowed)
				(footprints allowed)
			)
			(placement
				(enabled no)
				(sheetname "")
			)
			(fill
				(thermal_gap 0.5)
				(thermal_bridge_width 0.5)
				(island_removal_mode 0)
			)
			(polygon
				(pts
					(xy 419.0492 -18.4912) (xy 419.5572 -18.4912) (xy 419.5572 -18.1102) (xy 419.0492 -18.1102)
				)
			)
		)
		(zone
			(layer "F.Cu")
			(hatch none 0.5)
			(connect_pads
				(clearance 0)
			)
			(min_thickness 0.25)
			(keepout
				(tracks not_allowed)
				(vias allowed)
				(pads allowed)
				(copperpour not_allowed)
				(footprints allowed)
			)
			(placement
				(enabled no)
				(sheetname "")
			)
			(fill
				(thermal_gap 0.5)
				(thermal_bridge_width 0.5)
				(island_removal_mode 0)
			)
			(polygon
				(pts
					(xy 419.0492 -18.1102) (xy 419.5572 -18.1102) (xy 419.5572 -18.4912) (xy 419.0492 -18.4912)
				)
			)
		)
	)
	(footprint ""
		(layer "F.Cu")
		(at 383.286 1.651 90)
		(property "Reference" "R7G21"
			(at 0 0 90)
			(layer "F.SilkS")
			(hide yes)
			(effects
				(font
					(size 1.27 1.27)
				)
			)
		)
		(property "Value" ""
			(at 0 0 90)
			(layer "F.Fab")
			(effects
				(font
					(size 1.27 1.27)
				)
			)
		)
		(duplicate_pad_numbers_are_jumpers no)
		(fp_poly
			(pts
				(xy -0.2794 -0.1016) (xy 0.2794 -0.1016) (xy 0.2794 0.9906) (xy -0.2794 0.9906)
			)
			(stroke
				(width 0)
				(type default)
			)
			(fill no)
			(layer "F.CrtYd")
		)
		(fp_line
			(start 0.2794 -0.1016)
			(end -0.2794 -0.1016)
			(stroke
				(width 0.1)
				(type default)
			)
			(layer "F.Fab")
		)
		(fp_line
			(start -0.2794 -0.1016)
			(end -0.2794 0.9906)
			(stroke
				(width 0.1)
				(type default)
			)
			(layer "F.Fab")
		)
		(fp_line
			(start 0.2794 0.9906)
			(end 0.2794 -0.1016)
			(stroke
				(width 0.1)
				(type default)
			)
			(layer "F.Fab")
		)
		(fp_line
			(start -0.2794 0.9906)
			(end 0.2794 0.9906)
			(stroke
				(width 0.1)
				(type default)
			)
			(layer "F.Fab")
		)
		(pad "1" smd rect
			(at 0 0 90)
			(size 0.508 0.508)
			(layers "F.Cu" "F.Mask" "F.Paste")
			(net "JTAG_TDO")
		)
		(pad "2" smd rect
			(at 0 0.889 90)
			(size 0.508 0.508)
			(layers "F.Cu" "F.Mask" "F.Paste")
			(net "JTAG_TDO_R")
		)
		(zone
			(layer "F.Cu")
			(hatch none 0.5)
			(connect_pads
				(clearance 0)
			)
			(min_thickness 0.25)
			(keepout
				(tracks allowed)
				(vias not_allowed)
				(pads allowed)
				(copperpour not_allowed)
				(footprints allowed)
			)
			(placement
				(enabled no)
				(sheetname "")
			)
			(fill
				(thermal_gap 0.5)
				(thermal_bridge_width 0.5)
				(island_removal_mode 0)
			)
			(polygon
				(pts
					(xy 383.54 1.905) (xy 383.54 1.397) (xy 383.921 1.397) (xy 383.921 1.905)
				)
			)
		)
		(zone
			(layer "F.Cu")
			(hatch none 0.5)
			(connect_pads
				(clearance 0)
			)
			(min_thickness 0.25)
			(keepout
				(tracks not_allowed)
				(vias allowed)
				(pads allowed)
				(copperpour not_allowed)
				(footprints allowed)
			)
			(placement
				(enabled no)
				(sheetname "")
			)
			(fill
				(thermal_gap 0.5)
				(thermal_bridge_width 0.5)
				(island_removal_mode 0)
			)
			(polygon
				(pts
					(xy 383.921 1.905) (xy 383.921 1.397) (xy 383.54 1.397) (xy 383.54 1.905)
				)
			)
		)
	)
)
